# T6G (Grand Teton) — schematic netlist excerpt (pin names and nets, part order shuffled) for the footprints in the layout excerpt that follows; sources: Cadence DE-HDL packaged netlist, KiCad conversion of 04192023_DAF0TMB3IC0_F0TG_MB_C_brd_V02_OCP.brd

C993  Q_CAP  22UF 4V 20% X6S  pkg C0402  page 312 : A = P1V8_CPU0_RT3_1A ; B = GND
R2835  Q_RES  4.7K 5% CHIP  pkg 0402LF  page 127 : A = P3V3_AUX ; B = BIC_MONITER_N
C6721  Q_CAP_DIFFBUS  DIFF BUS_0.22UF 6.3V 20% X6S  pkg C0201  page 341 : \1\ = P5E_CPU1_P2_TX_BUF_C_DP<14> ; \2\ = P5E_CPU1_P2_TX_BUF_DP<14>

(kicad_pcb
	(version 20260206)
	(generator "pcbnew")
	(generator_version "10.0")
	(general
		(thickness 1.6)
		(legacy_teardrops no)
	)
	(paper "A4")
	(title_block
		(title "04192023_DAF0TMB3IC0_F0TG_MB_C_brd_V02_OCP.brd")
		(comment 1 "Grand Teton / footprints 4925-4927 of 8354")
	)
	(layers
		(0 "F.Cu" signal "TOP")
		(4 "In1.Cu" signal "GND")
		(6 "In2.Cu" signal "IN1")
		(8 "In3.Cu" signal "GND1")
		(10 "In4.Cu" signal "IN2")
		(12 "In5.Cu" signal "GND2")
		(14 "In6.Cu" signal "IN3")
		(16 "In7.Cu" signal "GND3")
		(18 "In8.Cu" signal "VCC")
		(20 "In9.Cu" signal "VCC1")
		(22 "In10.Cu" signal "GND4")
		(24 "In11.Cu" signal "IN4")
		(26 "In12.Cu" signal "GND5")
		(28 "In13.Cu" signal "IN5")
		(30 "In14.Cu" signal "GND6")
		(32 "In15.Cu" signal "IN6")
		(34 "In16.Cu" signal "GND7")
		(2 "B.Cu" signal "BOTTOM")
		(9 "F.Adhes" user "F.Adhesive")
		(11 "B.Adhes" user "B.Adhesive")
		(13 "F.Paste" user "Package Geometry/Pastemask Top")
		(15 "B.Paste" user "Package Geometry/Pastemask Bottom")
		(5 "F.SilkS" user "Ref Des/Silkscreen Top")
		(7 "B.SilkS" user "Ref Des/Silkscreen Bottom")
		(1 "F.Mask" user "Board Geometry/Soldermask Top")
		(3 "B.Mask" user "Board Geometry/Soldermask Bottom")
		(17 "Dwgs.User" user "User.Drawings")
		(19 "Cmts.User" user "User.Comments")
		(21 "Eco1.User" user "User.Eco1")
		(23 "Eco2.User" user "User.Eco2")
		(25 "Edge.Cuts" user "Board Geometry/Outline")
		(27 "Margin" user)
		(31 "F.CrtYd" user "Package Geometry/Place Bound Top")
		(29 "B.CrtYd" user "Package Geometry/Place Bound Bottom")
		(35 "F.Fab" user "Ref Des/Assembly Top")
		(33 "B.Fab" user "Ref Des/Assembly Bottom")
	)
	(footprint ""
		(layer "F.Cu")
		(at 170.970702 -439.740294 90)
		(property "Reference" "R2835"
			(at 0 0 90)
			(layer "F.SilkS")
			(hide yes)
			(effects
				(font
					(size 1.27 1.27)
				)
			)
		)
		(property "Value" ""
			(at 0 0 90)
			(layer "F.Fab")
			(effects
				(font
					(size 1.27 1.27)
				)
			)
		)
		(duplicate_pad_numbers_are_jumpers no)
		(fp_line
			(start 0.7874 -0.4064)
			(end 0.7874 0.4064)
			(stroke
				(width 0.1524)
				(type default)
			)
			(layer "F.SilkS")
		)
		(fp_line
			(start -0.7874 -0.4064)
			(end 0.7874 -0.4064)
			(stroke
				(width 0.1524)
				(type default)
			)
			(layer "F.SilkS")
		)
		(fp_line
			(start 0.7874 0.4064)
			(end -0.7874 0.4064)
			(stroke
				(width 0.1524)
				(type default)
			)
			(layer "F.SilkS")
		)
		(fp_line
			(start -0.7874 0.4064)
			(end -0.7874 -0.4064)
			(stroke
				(width 0.1524)
				(type default)
			)
			(layer "F.SilkS")
		)
		(fp_line
			(start -0.12065 -0.305054)
			(end -0.12065 -0.2794)
			(stroke
				(width 0.1)
				(type default)
			)
			(layer "F.Fab")
		)
		(fp_line
			(start -0.67945 -0.305054)
			(end -0.12065 -0.305054)
			(stroke
				(width 0.1)
				(type default)
			)
			(layer "F.Fab")
		)
		(fp_line
			(start 0.67945 -0.3048)
			(end 0.67945 0.3048)
			(stroke
				(width 0.1)
				(type default)
			)
			(layer "F.Fab")
		)
		(fp_line
			(start 0.12065 -0.3048)
			(end 0.67945 -0.3048)
			(stroke
				(width 0.1)
				(type default)
			)
			(layer "F.Fab")
		)
		(fp_line
			(start 0.12065 -0.2794)
			(end 0.12065 -0.3048)
			(stroke
				(width 0.1)
				(type default)
			)
			(layer "F.Fab")
		)
		(fp_line
			(start -0.12065 -0.2794)
			(end 0.12065 -0.2794)
			(stroke
				(width 0.1)
				(type default)
			)
			(layer "F.Fab")
		)
		(fp_line
			(start 0.120396 0.2794)
			(end -0.12065 0.2794)
			(stroke
				(width 0.1)
				(type default)
			)
			(layer "F.Fab")
		)
		(fp_line
			(start -0.12065 0.2794)
			(end -0.12065 0.3048)
			(stroke
				(width 0.1)
				(type default)
			)
			(layer "F.Fab")
		)
		(fp_line
			(start 0.67945 0.3048)
			(end 0.120396 0.3048)
			(stroke
				(width 0.1)
				(type default)
			)
			(layer "F.Fab")
		)
		(fp_line
			(start 0.120396 0.3048)
			(end 0.120396 0.2794)
			(stroke
				(width 0.1)
				(type default)
			)
			(layer "F.Fab")
		)
		(fp_line
			(start -0.12065 0.3048)
			(end -0.67945 0.3048)
			(stroke
				(width 0.1)
				(type default)
			)
			(layer "F.Fab")
		)
		(fp_line
			(start -0.67945 0.3048)
			(end -0.67945 -0.305054)
			(stroke
				(width 0.1)
				(type default)
			)
			(layer "F.Fab")
		)
		(pad "1" smd circle
			(at -0.40005 0 90)
			(size 0 0)
			(layers "F.Cu" "F.Mask" "F.Paste")
			(net "P3V3_AUX")
		)
		(pad "2" smd circle
			(at 0.40005 0 90)
			(size 0 0)
			(layers "F.Cu" "F.Mask" "F.Paste")
			(net "BIC_MONITER_N")
		)
	)
	(footprint ""
		(layer "F.Cu")
		(at 158.668466 -408.517344 -90)
		(property "Reference" "C6721"
			(at 0 0 270)
			(layer "F.SilkS")
			(hide yes)
			(effects
				(font
					(size 1.27 1.27)
				)
			)
		)
		(property "Value" ""
			(at 0 0 270)
			(layer "F.Fab")
			(effects
				(font
					(size 1.27 1.27)
				)
			)
		)
		(duplicate_pad_numbers_are_jumpers no)
		(fp_line
			(start -0.299974 0.150114)
			(end -0.299974 -0.150114)
			(stroke
				(width 0.1)
				(type default)
			)
			(layer "F.Fab")
		)
		(fp_line
			(start 0.299974 0.150114)
			(end -0.299974 0.150114)
			(stroke
				(width 0.1)
				(type default)
			)
			(layer "F.Fab")
		)
		(fp_line
			(start -0.299974 -0.150114)
			(end 0.299974 -0.150114)
			(stroke
				(width 0.1)
				(type default)
			)
			(layer "F.Fab")
		)
		(fp_line
			(start 0.299974 -0.150114)
			(end 0.299974 0.150114)
			(stroke
				(width 0.1)
				(type default)
			)
			(layer "F.Fab")
		)
		(pad "1" smd rect
			(at -0.2667 0 270)
			(size 0.3048 0.381)
			(layers "F.Cu" "F.Mask" "F.Paste")
			(net "P5E_CPU1_P2_TX_BUF_C_DP<14>")
		)
		(pad "2" smd rect
			(at 0.2667 0 270)
			(size 0.3048 0.381)
			(layers "F.Cu" "F.Mask" "F.Paste")
			(net "P5E_CPU1_P2_TX_BUF_DP<14>")
		)
	)
	(footprint ""
		(layer "F.Cu")
		(at 392.593576 -394.82268 90)
		(property "Reference" "C993"
			(at 0 0 90)
			(layer "F.SilkS")
			(hide yes)
			(effects
				(font
					(size 1.27 1.27)
				)
			)
		)
		(property "Value" ""
			(at 0 0 90)
			(layer "F.Fab")
			(effects
				(font
					(size 1.27 1.27)
				)
			)
		)
		(duplicate_pad_numbers_are_jumpers no)
		(fp_line
			(start 0.7874 -0.4064)
			(end 0.7874 0.4064)
			(stroke
				(width 0.1524)
				(type default)
			)
			(layer "F.SilkS")
		)
		(fp_line
			(start -0.7874 -0.4064)
			(end 0.7874 -0.4064)
			(stroke
				(width 0.1524)
				(type default)
			)
			(layer "F.SilkS")
		)
		(fp_line
			(start 0.7874 0.4064)
			(end -0.7874 0.4064)
			(stroke
				(width 0.1524)
				(type default)
			)
			(layer "F.SilkS")
		)
		(fp_line
			(start -0.7874 0.4064)
			(end -0.7874 -0.4064)
			(stroke
				(width 0.1524)
				(type default)
			)
			(layer "F.SilkS")
		)
		(fp_line
			(start -0.12065 -0.305054)
			(end -0.12065 -0.2794)
			(stroke
				(width 0.1)
				(type default)
			)
			(layer "F.Fab")
		)
		(fp_line
			(start -0.67945 -0.305054)
			(end -0.12065 -0.305054)
			(stroke
				(width 0.1)
				(type default)
			)
			(layer "F.Fab")
		)
		(fp_line
			(start 0.67945 -0.3048)
			(end 0.67945 0.3048)
			(stroke
				(width 0.1)
				(type default)
			)
			(layer "F.Fab")
		)
		(fp_line
			(start 0.12065 -0.3048)
			(end 0.67945 -0.3048)
			(stroke
				(width 0.1)
				(type default)
			)
			(layer "F.Fab")
		)
		(fp_line
			(start 0.12065 -0.2794)
			(end 0.12065 -0.3048)
			(stroke
				(width 0.1)
				(type default)
			)
			(layer "F.Fab")
		)
		(fp_line
			(start -0.12065 -0.2794)
			(end 0.12065 -0.2794)
			(stroke
				(width 0.1)
				(type default)
			)
			(layer "F.Fab")
		)
		(fp_line
			(start 0.120396 0.2794)
			(end -0.12065 0.2794)
			(stroke
				(width 0.1)
				(type default)
			)
			(layer "F.Fab")
		)
		(fp_line
			(start -0.12065 0.2794)
			(end -0.12065 0.3048)
			(stroke
				(width 0.1)
				(type default)
			)
			(layer "F.Fab")
		)
		(fp_line
			(start 0.67945 0.3048)
			(end 0.120396 0.3048)
			(stroke
				(width 0.1)
				(type default)
			)
			(layer "F.Fab")
		)
		(fp_line
			(start 0.120396 0.3048)
			(end 0.120396 0.2794)
			(stroke
				(width 0.1)
				(type default)
			)
			(layer "F.Fab")
		)
		(fp_line
			(start -0.12065 0.3048)
			(end -0.67945 0.3048)
			(stroke
				(width 0.1)
				(type default)
			)
			(layer "F.Fab")
		)
		(fp_line
			(start -0.67945 0.3048)
			(end -0.67945 -0.305054)
			(stroke
				(width 0.1)
				(type default)
			)
			(layer "F.Fab")
		)
		(pad "1" smd circle
			(at -0.40005 0 90)
			(size 0 0)
			(layers "F.Cu" "F.Mask" "F.Paste")
			(net "P1V8_CPU0_RT3_1A")
		)
		(pad "2" smd circle
			(at 0.40005 0 90)
			(size 0 0)
			(layers "F.Cu" "F.Mask" "F.Paste")
			(net "GND")
		)
	)
)
